# S9S_MB_2U (Grand Teton) — schematic netlist excerpt (pin names and nets, part order shuffled) for the footprints in the layout excerpt that follows; sources: Cadence DE-HDL packaged netlist, KiCad conversion of 03242023_DA0F0TMBIJ0_F0T_Motherboard_J_brd_V01_OCP.brd

PU24_P1_7  ISL99390FRZTR5935  ISL99390FRZ-TR5935 IC  pkg QFN21_6X5XB  page 288
  VOS  = PVCCIN_CPU1_VOS7
  AGND  = GND
  VCC  = PVCCIN_CPU1_VDD7
  PVCC  = PVCCIN_CPU1_PVCC
  PGND1  = GND
  GL1  = NC
  PGND2  = GND
  SW  = SW_PVCCIN_CPU1_SW7
  VIN1  = SW_P12V_PVCCIN_CPU1_FLT
  VIN2  = SW_P12V_PVCCIN_CPU1_FLT
  DNC  = NC
  PHASE  = SW_PVCCIN_CPU1_BOOTR7
  BOOT  = SW_PVCCIN_CPU1_BOOT7
  PWM  = PVCCIN_CPU1_PWM7
  EN  = PVCCIN_CPU1_VDD7
  TOUT_FLT  = PVCCIN_CPU1_ATSEN
  LSET  = PVCCIN_CPU1_LSET7
  IOUT  = PVCCIN_CPU1_IMON7
  REFIN  = PVCCIN_CPU1_VREF
  PGND3  = GND
  GL2  = NC

(kicad_pcb
	(version 20260206)
	(generator "pcbnew")
	(generator_version "10.0")
	(general
		(thickness 1.6)
		(legacy_teardrops no)
	)
	(paper "A4")
	(title_block
		(title "03242023_DA0F0TMBIJ0_F0T_Motherboard_J_brd_V01_OCP.brd")
		(comment 1 "Grand Teton / footprints 2609-2609 of 6105")
	)
	(layers
		(0 "F.Cu" signal "TOP")
		(4 "In1.Cu" signal "GND")
		(6 "In2.Cu" signal "IN1")
		(8 "In3.Cu" signal "GND1")
		(10 "In4.Cu" signal "IN2")
		(12 "In5.Cu" signal "GND2")
		(14 "In6.Cu" signal "IN3")
		(16 "In7.Cu" signal "GND3")
		(18 "In8.Cu" signal "VCC")
		(20 "In9.Cu" signal "VCC1")
		(22 "In10.Cu" signal "GND4")
		(24 "In11.Cu" signal "IN4")
		(26 "In12.Cu" signal "GND5")
		(28 "In13.Cu" signal "IN5")
		(30 "In14.Cu" signal "GND6")
		(32 "In15.Cu" signal "IN6")
		(34 "In16.Cu" signal "GND7")
		(2 "B.Cu" signal "BOTTOM")
		(9 "F.Adhes" user "F.Adhesive")
		(11 "B.Adhes" user "B.Adhesive")
		(13 "F.Paste" user "Package Geometry/Pastemask Top")
		(15 "B.Paste" user "Package Geometry/Pastemask Bottom")
		(5 "F.SilkS" user "Ref Des/Silkscreen Top")
		(7 "B.SilkS" user "Ref Des/Silkscreen Bottom")
		(1 "F.Mask" user "Board Geometry/Soldermask Top")
		(3 "B.Mask" user "Board Geometry/Soldermask Bottom")
		(17 "Dwgs.User" user "User.Drawings")
		(19 "Cmts.User" user "User.Comments")
		(21 "Eco1.User" user "User.Eco1")
		(23 "Eco2.User" user "User.Eco2")
		(25 "Edge.Cuts" user "Board Geometry/Outline")
		(27 "Margin" user)
		(31 "F.CrtYd" user "Package Geometry/Place Bound Top")
		(29 "B.CrtYd" user "Package Geometry/Place Bound Bottom")
		(35 "F.Fab" user "Ref Des/Assembly Top")
		(33 "B.Fab" user "Ref Des/Assembly Bottom")
	)
	(footprint ""
		(layer "F.Cu")
		(at 80.67675 -342.917018)
		(property "Reference" "PU24_P1_7"
			(at -11.33475 4.14274 0)
			(unlocked yes)
			(layer "F.SilkS")
			(effects
				(font
					(size 0.7874 0.5842)
					(thickness 0.1524)
				)
				(justify left)
			)
		)
		(property "Value" ""
			(at 0 0 0)
			(layer "F.Fab")
			(effects
				(font
					(size 1.27 1.27)
				)
			)
		)
		(duplicate_pad_numbers_are_jumpers no)
		(fp_line
			(start -2.500122 -2.999994)
			(end -2.24409 -2.999994)
			(stroke
				(width 0.1524)
				(type default)
			)
			(layer "F.SilkS")
		)
		(fp_line
			(start -2.500122 -2.529078)
			(end -2.500122 -2.999994)
			(stroke
				(width 0.1524)
				(type default)
			)
			(layer "F.SilkS")
		)
		(fp_line
			(start -2.500122 0.6604)
			(end -2.500122 0.229108)
			(stroke
				(width 0.1524)
				(type default)
			)
			(layer "F.SilkS")
		)
		(fp_line
			(start -2.500122 2.999994)
			(end -2.500122 2.339594)
			(stroke
				(width 0.1524)
				(type default)
			)
			(layer "F.SilkS")
		)
		(fp_line
			(start -2.2987 2.999994)
			(end -2.500122 2.999994)
			(stroke
				(width 0.1524)
				(type default)
			)
			(layer "F.SilkS")
		)
		(fp_line
			(start 2.31394 -2.999994)
			(end 2.500122 -2.999994)
			(stroke
				(width 0.1524)
				(type default)
			)
			(layer "F.SilkS")
		)
		(fp_line
			(start 2.500122 -2.999994)
			(end 2.500122 -2.44348)
			(stroke
				(width 0.1524)
				(type default)
			)
			(layer "F.SilkS")
		)
		(fp_line
			(start 2.500122 2.339594)
			(end 2.500122 2.999994)
			(stroke
				(width 0.1524)
				(type default)
			)
			(layer "F.SilkS")
		)
		(fp_line
			(start 2.500122 2.999994)
			(end 2.2987 2.999994)
			(stroke
				(width 0.1524)
				(type default)
			)
			(layer "F.SilkS")
		)
		(fp_poly
			(pts
				(xy -3.36423 -3.401822) (xy -2.648712 -2.831592) (xy -2.622296 -3.736594)
			)
			(stroke
				(width 0)
				(type default)
			)
			(fill yes)
			(layer "F.SilkS")
		)
		(fp_line
			(start -2.500122 -2.999994)
			(end 2.500122 -2.999994)
			(stroke
				(width 0.1)
				(type default)
			)
			(layer "F.Fab")
		)
		(fp_line
			(start -2.500122 2.999994)
			(end -2.500122 -2.999994)
			(stroke
				(width 0.1)
				(type default)
			)
			(layer "F.Fab")
		)
		(fp_line
			(start 2.500122 -2.999994)
			(end 2.500122 2.999994)
			(stroke
				(width 0.1)
				(type default)
			)
			(layer "F.Fab")
		)
		(fp_line
			(start 2.500122 2.999994)
			(end -2.500122 2.999994)
			(stroke
				(width 0.1)
				(type default)
			)
			(layer "F.Fab")
		)
		(fp_poly
			(pts
				(xy -4.218432 -2.783078) (xy -4.218432 -1.767078) (xy -3.202432 -2.275078)
			)
			(stroke
				(width 0)
				(type default)
			)
			(fill yes)
			(layer "F.Fab")
		)
		(pad "1" smd rect
			(at -2.400046 -2.275078 90)
			(size 0.2286 0.6096)
			(layers "F.Cu" "F.Mask" "F.Paste")
			(net "PVCCIN_CPU1_VOS7")
		)
		(pad "2" smd rect
			(at -2.400046 -1.82499 90)
			(size 0.2286 0.6096)
			(layers "F.Cu" "F.Mask" "F.Paste")
			(net "GND")
		)
		(pad "3" smd rect
			(at -2.400046 -1.374902 90)
			(size 0.2286 0.6096)
			(layers "F.Cu" "F.Mask" "F.Paste")
			(net "PVCCIN_CPU1_VDD7")
		)
		(pad "4" smd rect
			(at -2.400046 -0.925068 90)
			(size 0.2286 0.6096)
			(layers "F.Cu" "F.Mask" "F.Paste")
			(net "PVCCIN_CPU1_PVCC")
		)
		(pad "5" smd rect
			(at -2.400046 -0.47498 90)
			(size 0.2286 0.6096)
			(layers "F.Cu" "F.Mask" "F.Paste")
			(net "GND")
		)
		(pad "6" smd rect
			(at -2.400046 -0.024892 90)
			(size 0.2286 0.6096)
			(layers "F.Cu" "F.Mask" "F.Paste")
			(net "Net_8538")
		)
		(pad "7_9-20_24" smd circle
			(at 0 1.150112 90)
			(size 0 0)
			(layers "F.Cu" "F.Mask" "F.Paste")
			(net "GND")
		)
		(pad "10_19" smd rect
			(at 0 2.899918 90)
			(size 0.6096 4.318)
			(layers "F.Cu" "F.Mask" "F.Paste")
			(net "SW_PVCCIN_CPU1_SW7")
		)
		(pad "25_29" smd rect
			(at 1.549908 -1.279906 270)
			(size 2.0574 2.3114)
			(layers "F.Cu" "F.Mask" "F.Paste")
			(net "SW_P12V_PVCCIN_CPU1_FLT")
		)
		(pad "30" smd rect
			(at 2.05994 -2.899918)
			(size 0.2286 0.6096)
			(layers "F.Cu" "F.Mask" "F.Paste")
			(net "SW_P12V_PVCCIN_CPU1_FLT")
		)
		(pad "31" smd rect
			(at 1.610106 -2.899918)
			(size 0.2286 0.6096)
			(layers "F.Cu" "F.Mask" "F.Paste")
			(net "Net_8539")
		)
		(pad "32" smd rect
			(at 1.160018 -2.899918)
			(size 0.2286 0.6096)
			(layers "F.Cu" "F.Mask" "F.Paste")
			(net "SW_PVCCIN_CPU1_BOOTR7")
		)
		(pad "33" smd rect
			(at 0.70993 -2.899918)
			(size 0.2286 0.6096)
			(layers "F.Cu" "F.Mask" "F.Paste")
			(net "SW_PVCCIN_CPU1_BOOT7")
		)
		(pad "34" smd rect
			(at 0.260096 -2.899918)
			(size 0.2286 0.6096)
			(layers "F.Cu" "F.Mask" "F.Paste")
			(net "PVCCIN_CPU1_PWM7")
		)
		(pad "35" smd rect
			(at -0.189992 -2.899918)
			(size 0.2286 0.6096)
			(layers "F.Cu" "F.Mask" "F.Paste")
			(net "PVCCIN_CPU1_VDD7")
		)
		(pad "36" smd rect
			(at -0.64008 -2.899918)
			(size 0.2286 0.6096)
			(layers "F.Cu" "F.Mask" "F.Paste")
			(net "PVCCIN_CPU1_ATSEN")
		)
		(pad "37" smd rect
			(at -1.089914 -2.899918)
			(size 0.2286 0.6096)
			(layers "F.Cu" "F.Mask" "F.Paste")
			(net "PVCCIN_CPU1_LSET7")
		)
		(pad "38" smd rect
			(at -1.540002 -2.899918)
			(size 0.2286 0.6096)
			(layers "F.Cu" "F.Mask" "F.Paste")
			(net "PVCCIN_CPU1_IMON7")
		)
		(pad "39" smd rect
			(at -1.99009 -2.899918)
			(size 0.2286 0.6096)
			(layers "F.Cu" "F.Mask" "F.Paste")
			(net "PVCCIN_CPU1_VREF")
		)
		(pad "40" smd rect
			(at -0.87503 -1.27508)
			(size 1.7526 1.9558)
			(layers "F.Cu" "F.Mask" "F.Paste")
			(net "GND")
		)
		(pad "41" smd rect
			(at -1.525016 0.249936 270)
			(size 0.3048 0.4572)
			(layers "F.Cu" "F.Mask" "F.Paste")
			(net "Net_8537")
		)
		(zone
			(layer "F.Cu")
			(hatch none 0.5)
			(connect_pads
				(clearance 0)
			)
			(min_thickness 0.25)
			(keepout
				(tracks not_allowed)
				(vias allowed)
				(pads allowed)
				(copperpour not_allowed)
				(footprints allowed)
			)
			(placement
				(enabled no)
				(sheetname "")
			)
			(fill
				(thermal_gap 0.5)
				(thermal_bridge_width 0.5)
				(island_removal_mode 0)
			)
			(polygon
				(pts
					(xy 78.176628 -339.917024) (xy 78.176628 -340.666324) (xy 83.176872 -340.666324) (xy 83.176872 -339.917024)
					(xy 82.9691 -339.917024) (xy 82.9691 -340.23427) (xy 82.88655 -340.31682) (xy 82.88655 -340.3727)
					(xy 78.46695 -340.3727) (xy 78.46695 -340.24316) (xy 78.41488 -340.19109) (xy 78.41488 -339.917024)
				)
			)
		)
	)
)
